# Kria K26 Devboard — assets/stackup.csv
Name;Type;Material;Thickness[mm];Constant;User-Name
F.SilkS;Top Silk Screen;;;;F_Silkscreen
F.Paste;Top Solder Paste;;;;F_Paste
F.Mask;Top Solder Mask;;0.01;;F_Mask
F.Cu;copper;;0.035;;F_Cu
dielectric 1;prepreg;PR2116;0.12;4.3;dielectric 1
In1.Cu;copper;;0.018;;In1_Cu
dielectric 2;core;IS400;0.2;3.9;dielectric 2
In2.Cu;copper;;0.018;;In2_Cu
dielectric 3 (1/2);prepreg;PR2116;0.12;4.3;dielectric 3 (1/2)
dielectric 3 (2/2);prepreg;PR2116;0.12;4.3;dielectric 3 (2/2)
In3.Cu;copper;;0.018;;In3_Cu
dielectric 4;core;IS400;0.2;3.9;dielectric 4
In4.Cu;copper;;0.018;;In4_Cu
dielectric 5 (1/2);prepreg;PR2116;0.12;4.3;dielectric 5 (1/2)
dielectric 5 (2/2);prepreg;PR2116;0.12;4.3;dielectric 5 (2/2)
In5.Cu;copper;;0.018;;In5_Cu
dielectric 6;core;IS400;0.2;3.9;dielectric 6
In6.Cu;copper;;0.018;;In6_Cu
dielectric 7;prepreg;PR2116;0.12;4.3;dielectric 7
B.Cu;copper;;0.035;;B_Cu
B.Mask;Bottom Solder Mask;;0.01;;B_Mask
B.Paste;Bottom Solder Paste;;;;B_Paste
B.SilkS;Bottom Silk Screen;;;;B_Silkscreen
